# T6G (Grand Teton) — schematic netlist excerpt (pin names and nets, part order shuffled) for the footprints in the layout excerpt that follows; sources: Cadence DE-HDL packaged netlist, KiCad conversion of 04192023_DAF0TMB3IC0_F0TG_MB_C_brd_V02_OCP.brd

R8301  Q_RES  0 5% CHIP  pkg 0402LF  page 193 : A = PVDDCR_CPU0_P0_OCP_N ; B = PVDDCR_CPU0_P0_OCP_N_R
R393  Q_RES  2.2K 5% CHIP  pkg 0402LF  page 27 : A = CPU0_SA0 ; B = GND

(kicad_pcb
	(version 20260206)
	(generator "pcbnew")
	(generator_version "10.0")
	(general
		(thickness 1.6)
		(legacy_teardrops no)
	)
	(paper "A4")
	(title_block
		(title "04192023_DAF0TMB3IC0_F0TG_MB_C_brd_V02_OCP.brd")
		(comment 1 "Grand Teton / footprints 5238-5239 of 8354")
	)
	(layers
		(0 "F.Cu" signal "TOP")
		(4 "In1.Cu" signal "GND")
		(6 "In2.Cu" signal "IN1")
		(8 "In3.Cu" signal "GND1")
		(10 "In4.Cu" signal "IN2")
		(12 "In5.Cu" signal "GND2")
		(14 "In6.Cu" signal "IN3")
		(16 "In7.Cu" signal "GND3")
		(18 "In8.Cu" signal "VCC")
		(20 "In9.Cu" signal "VCC1")
		(22 "In10.Cu" signal "GND4")
		(24 "In11.Cu" signal "IN4")
		(26 "In12.Cu" signal "GND5")
		(28 "In13.Cu" signal "IN5")
		(30 "In14.Cu" signal "GND6")
		(32 "In15.Cu" signal "IN6")
		(34 "In16.Cu" signal "GND7")
		(2 "B.Cu" signal "BOTTOM")
		(9 "F.Adhes" user "F.Adhesive")
		(11 "B.Adhes" user "B.Adhesive")
		(13 "F.Paste" user "Package Geometry/Pastemask Top")
		(15 "B.Paste" user "Package Geometry/Pastemask Bottom")
		(5 "F.SilkS" user "Ref Des/Silkscreen Top")
		(7 "B.SilkS" user "Ref Des/Silkscreen Bottom")
		(1 "F.Mask" user "Board Geometry/Soldermask Top")
		(3 "B.Mask" user "Board Geometry/Soldermask Bottom")
		(17 "Dwgs.User" user "User.Drawings")
		(19 "Cmts.User" user "User.Comments")
		(21 "Eco1.User" user "User.Eco1")
		(23 "Eco2.User" user "User.Eco2")
		(25 "Edge.Cuts" user "Board Geometry/Outline")
		(27 "Margin" user)
		(31 "F.CrtYd" user "Package Geometry/Place Bound Top")
		(29 "B.CrtYd" user "Package Geometry/Place Bound Bottom")
		(35 "F.Fab" user "Ref Des/Assembly Top")
		(33 "B.Fab" user "Ref Des/Assembly Bottom")
	)
	(footprint ""
		(layer "B.Cu")
		(at 384.113278 -143.250158)
		(property "Reference" "R8301"
			(at 0 0 0)
			(layer "B.SilkS")
			(hide yes)
			(effects
				(font
					(size 1.27 1.27)
				)
				(justify mirror)
			)
		)
		(property "Value" ""
			(at 0 0 0)
			(layer "B.Fab")
			(effects
				(font
					(size 1.27 1.27)
				)
				(justify mirror)
			)
		)
		(duplicate_pad_numbers_are_jumpers no)
		(fp_line
			(start -0.7874 -0.4064)
			(end -0.7874 0.4064)
			(stroke
				(width 0.1524)
				(type default)
			)
			(layer "B.SilkS")
		)
		(fp_line
			(start -0.7874 0.4064)
			(end 0.7874 0.4064)
			(stroke
				(width 0.1524)
				(type default)
			)
			(layer "B.SilkS")
		)
		(fp_line
			(start 0.7874 -0.4064)
			(end -0.7874 -0.4064)
			(stroke
				(width 0.1524)
				(type default)
			)
			(layer "B.SilkS")
		)
		(fp_line
			(start 0.7874 0.4064)
			(end 0.7874 -0.4064)
			(stroke
				(width 0.1524)
				(type default)
			)
			(layer "B.SilkS")
		)
		(fp_line
			(start -0.67945 -0.3048)
			(end -0.67945 0.3048)
			(stroke
				(width 0.1)
				(type default)
			)
			(layer "B.Fab")
		)
		(fp_line
			(start -0.67945 0.3048)
			(end -0.120396 0.3048)
			(stroke
				(width 0.1)
				(type default)
			)
			(layer "B.Fab")
		)
		(fp_line
			(start -0.12065 -0.3048)
			(end -0.67945 -0.3048)
			(stroke
				(width 0.1)
				(type default)
			)
			(layer "B.Fab")
		)
		(fp_line
			(start -0.12065 -0.2794)
			(end -0.12065 -0.3048)
			(stroke
				(width 0.1)
				(type default)
			)
			(layer "B.Fab")
		)
		(fp_line
			(start -0.120396 0.2794)
			(end 0.12065 0.2794)
			(stroke
				(width 0.1)
				(type default)
			)
			(layer "B.Fab")
		)
		(fp_line
			(start -0.120396 0.3048)
			(end -0.120396 0.2794)
			(stroke
				(width 0.1)
				(type default)
			)
			(layer "B.Fab")
		)
		(fp_line
			(start 0.12065 -0.305054)
			(end 0.12065 -0.2794)
			(stroke
				(width 0.1)
				(type default)
			)
			(layer "B.Fab")
		)
		(fp_line
			(start 0.12065 -0.2794)
			(end -0.12065 -0.2794)
			(stroke
				(width 0.1)
				(type default)
			)
			(layer "B.Fab")
		)
		(fp_line
			(start 0.12065 0.2794)
			(end 0.12065 0.3048)
			(stroke
				(width 0.1)
				(type default)
			)
			(layer "B.Fab")
		)
		(fp_line
			(start 0.12065 0.3048)
			(end 0.67945 0.3048)
			(stroke
				(width 0.1)
				(type default)
			)
			(layer "B.Fab")
		)
		(fp_line
			(start 0.67945 -0.305054)
			(end 0.12065 -0.305054)
			(stroke
				(width 0.1)
				(type default)
			)
			(layer "B.Fab")
		)
		(fp_line
			(start 0.67945 0.3048)
			(end 0.67945 -0.305054)
			(stroke
				(width 0.1)
				(type default)
			)
			(layer "B.Fab")
		)
		(pad "1" smd circle
			(at 0.40005 0 180)
			(size 0 0)
			(layers "B.Cu" "B.Mask" "B.Paste")
			(net "PVDDCR_CPU0_P0_OCP_N")
		)
		(pad "2" smd circle
			(at -0.40005 0 180)
			(size 0 0)
			(layers "B.Cu" "B.Mask" "B.Paste")
			(net "PVDDCR_CPU0_P0_OCP_N_R")
		)
	)
	(footprint ""
		(layer "B.Cu")
		(at 339.846158 -309.214012 -90)
		(property "Reference" "R393"
			(at 0 0 90)
			(layer "B.SilkS")
			(hide yes)
			(effects
				(font
					(size 1.27 1.27)
				)
				(justify mirror)
			)
		)
		(property "Value" ""
			(at 0 0 90)
			(layer "B.Fab")
			(effects
				(font
					(size 1.27 1.27)
				)
				(justify mirror)
			)
		)
		(duplicate_pad_numbers_are_jumpers no)
		(fp_line
			(start -0.7874 0.4064)
			(end 0.7874 0.4064)
			(stroke
				(width 0.1524)
				(type default)
			)
			(layer "B.SilkS")
		)
		(fp_line
			(start 0.7874 0.4064)
			(end 0.7874 -0.4064)
			(stroke
				(width 0.1524)
				(type default)
			)
			(layer "B.SilkS")
		)
		(fp_line
			(start -0.7874 -0.4064)
			(end -0.7874 0.4064)
			(stroke
				(width 0.1524)
				(type default)
			)
			(layer "B.SilkS")
		)
		(fp_line
			(start 0.7874 -0.4064)
			(end -0.7874 -0.4064)
			(stroke
				(width 0.1524)
				(type default)
			)
			(layer "B.SilkS")
		)
		(fp_line
			(start -0.67945 0.3048)
			(end -0.120396 0.3048)
			(stroke
				(width 0.1)
				(type default)
			)
			(layer "B.Fab")
		)
		(fp_line
			(start -0.120396 0.3048)
			(end -0.120396 0.2794)
			(stroke
				(width 0.1)
				(type default)
			)
			(layer "B.Fab")
		)
		(fp_line
			(start 0.12065 0.3048)
			(end 0.67945 0.3048)
			(stroke
				(width 0.1)
				(type default)
			)
			(layer "B.Fab")
		)
		(fp_line
			(start 0.67945 0.3048)
			(end 0.67945 -0.305054)
			(stroke
				(width 0.1)
				(type default)
			)
			(layer "B.Fab")
		)
		(fp_line
			(start -0.120396 0.2794)
			(end 0.12065 0.2794)
			(stroke
				(width 0.1)
				(type default)
			)
			(layer "B.Fab")
		)
		(fp_line
			(start 0.12065 0.2794)
			(end 0.12065 0.3048)
			(stroke
				(width 0.1)
				(type default)
			)
			(layer "B.Fab")
		)
		(fp_line
			(start -0.12065 -0.2794)
			(end -0.12065 -0.3048)
			(stroke
				(width 0.1)
				(type default)
			)
			(layer "B.Fab")
		)
		(fp_line
			(start 0.12065 -0.2794)
			(end -0.12065 -0.2794)
			(stroke
				(width 0.1)
				(type default)
			)
			(layer "B.Fab")
		)
		(fp_line
			(start -0.67945 -0.3048)
			(end -0.67945 0.3048)
			(stroke
				(width 0.1)
				(type default)
			)
			(layer "B.Fab")
		)
		(fp_line
			(start -0.12065 -0.3048)
			(end -0.67945 -0.3048)
			(stroke
				(width 0.1)
				(type default)
			)
			(layer "B.Fab")
		)
		(fp_line
			(start 0.12065 -0.305054)
			(end 0.12065 -0.2794)
			(stroke
				(width 0.1)
				(type default)
			)
			(layer "B.Fab")
		)
		(fp_line
			(start 0.67945 -0.305054)
			(end 0.12065 -0.305054)
			(stroke
				(width 0.1)
				(type default)
			)
			(layer "B.Fab")
		)
		(pad "1" smd circle
			(at 0.40005 0 90)
			(size 0 0)
			(layers "B.Cu" "B.Mask" "B.Paste")
			(net "CPU0_SA0")
		)
		(pad "2" smd circle
			(at -0.40005 0 90)
			(size 0 0)
			(layers "B.Cu" "B.Mask" "B.Paste")
			(net "GND")
		)
	)
)
